# BASEBOARD_FAB2 (Tioga Pass) — schematic netlist excerpt (pin names and nets, part order shuffled) for the footprints in the layout excerpt that follows; sources: Cadence DE-HDL packaged netlist, KiCad conversion of Wiwynn_Tioga_Pass_MB.brd

C5L13  CAP_A  47UF 4V 20% X5R  pkg 0603V  page 220 : A = PVDDQ_DEF ; B = GND
R1U29  RES  5.11K 1% CHIP  pkg 0402  page 169 : A = P5V ; B = A_P5V_SCALED
C3P50  CAP  1.0UF 16V 10% X6S  pkg 0402  page 92 : A = P3V3 ; B = GND

(kicad_pcb
	(version 20260206)
	(generator "pcbnew")
	(generator_version "10.0")
	(general
		(thickness 1.6)
		(legacy_teardrops no)
	)
	(paper "A4")
	(title_block
		(title "Wiwynn_Tioga_Pass_MB.brd")
		(comment 1 "Tioga Pass / footprints 3299-3301 of 4770")
	)
	(layers
		(0 "F.Cu" signal "TOP")
		(4 "In1.Cu" signal "L2GND")
		(6 "In2.Cu" signal "L3")
		(8 "In3.Cu" signal "L4GND")
		(10 "In4.Cu" signal "L5")
		(12 "In5.Cu" signal "L6GND")
		(14 "In6.Cu" signal "L7VCC")
		(16 "In7.Cu" signal "L8VCC")
		(18 "In8.Cu" signal "L9GND")
		(20 "In9.Cu" signal "L10")
		(22 "In10.Cu" signal "L11GND")
		(24 "In11.Cu" signal "L12")
		(26 "In12.Cu" signal "L13GND")
		(2 "B.Cu" signal "BOTTOM")
		(9 "F.Adhes" user "F.Adhesive")
		(11 "B.Adhes" user "B.Adhesive")
		(13 "F.Paste" user "Package Geometry/Pastemask Top")
		(15 "B.Paste" user "Package Geometry/Pastemask Bottom")
		(5 "F.SilkS" user "Ref Des/Silkscreen Top")
		(7 "B.SilkS" user "Ref Des/Silkscreen Bottom")
		(1 "F.Mask" user "Board Geometry/Soldermask Top")
		(3 "B.Mask" user "Board Geometry/Soldermask Bottom")
		(17 "Dwgs.User" user "User.Drawings")
		(19 "Cmts.User" user "User.Comments")
		(21 "Eco1.User" user "User.Eco1")
		(23 "Eco2.User" user "User.Eco2")
		(25 "Edge.Cuts" user "Board Geometry/Outline")
		(27 "Margin" user)
		(31 "F.CrtYd" user "Package Geometry/Place Bound Top")
		(29 "B.CrtYd" user "Package Geometry/Place Bound Bottom")
		(35 "F.Fab" user "Ref Des/Assembly Top")
		(33 "B.Fab" user "Ref Des/Assembly Bottom")
	)
	(footprint ""
		(layer "B.Cu")
		(at 245.7577 -145.0086 -90)
		(property "Reference" "C5L13"
			(at -1.848866 0.752348 270)
			(unlocked yes)
			(layer "B.SilkS")
			(effects
				(font
					(size 1.27 0.9652)
					(thickness 0.1524)
				)
				(justify mirror)
			)
		)
		(property "Value" ""
			(at 0 0 90)
			(layer "B.Fab")
			(effects
				(font
					(size 1.27 1.27)
				)
				(justify mirror)
			)
		)
		(duplicate_pad_numbers_are_jumpers no)
		(fp_rect
			(start 0.500126 1.598422)
			(end -0.500126 -0.201422)
			(stroke
				(width 0)
				(type default)
			)
			(fill no)
			(layer "B.CrtYd")
		)
		(fp_line
			(start -0.500126 1.598422)
			(end 0.500126 1.598422)
			(stroke
				(width 0.1)
				(type default)
			)
			(layer "B.Fab")
		)
		(fp_line
			(start 0.500126 1.598422)
			(end 0.500126 -0.201422)
			(stroke
				(width 0.1)
				(type default)
			)
			(layer "B.Fab")
		)
		(fp_line
			(start -0.500126 -0.201422)
			(end -0.500126 1.598422)
			(stroke
				(width 0.1)
				(type default)
			)
			(layer "B.Fab")
		)
		(fp_line
			(start 0.500126 -0.201422)
			(end -0.500126 -0.201422)
			(stroke
				(width 0.1)
				(type default)
			)
			(layer "B.Fab")
		)
		(pad "1" smd rect
			(at 0 0 180)
			(size 0.889 0.9906)
			(layers "B.Cu" "B.Mask" "B.Paste")
			(net "PVDDQ_DEF")
		)
		(pad "2" smd rect
			(at 0 1.397 180)
			(size 0.889 0.9906)
			(layers "B.Cu" "B.Mask" "B.Paste")
			(net "GND")
		)
		(zone
			(layer "B.Cu")
			(hatch none 0.5)
			(connect_pads
				(clearance 0)
			)
			(min_thickness 0.25)
			(keepout
				(tracks allowed)
				(vias not_allowed)
				(pads allowed)
				(copperpour not_allowed)
				(footprints allowed)
			)
			(placement
				(enabled no)
				(sheetname "")
			)
			(fill
				(thermal_gap 0.5)
				(thermal_bridge_width 0.5)
				(island_removal_mode 0)
			)
			(polygon
				(pts
					(xy 244.8052 -144.5133) (xy 245.3132 -144.5133) (xy 245.3132 -145.5039) (xy 244.8052 -145.5039)
				)
			)
		)
		(zone
			(layer "B.Cu")
			(hatch none 0.5)
			(connect_pads
				(clearance 0)
			)
			(min_thickness 0.25)
			(keepout
				(tracks not_allowed)
				(vias allowed)
				(pads allowed)
				(copperpour not_allowed)
				(footprints allowed)
			)
			(placement
				(enabled no)
				(sheetname "")
			)
			(fill
				(thermal_gap 0.5)
				(thermal_bridge_width 0.5)
				(island_removal_mode 0)
			)
			(polygon
				(pts
					(xy 244.8052 -144.5133) (xy 245.3132 -144.5133) (xy 245.3132 -145.5039) (xy 244.8052 -145.5039)
				)
			)
		)
	)
	(footprint ""
		(layer "B.Cu")
		(at 363.4486 -62.6999 180)
		(property "Reference" "C3P50"
			(at 0 0 0)
			(layer "B.SilkS")
			(hide yes)
			(effects
				(font
					(size 1.27 1.27)
				)
				(justify mirror)
			)
		)
		(property "Value" ""
			(at 0 0 0)
			(layer "B.Fab")
			(effects
				(font
					(size 1.27 1.27)
				)
				(justify mirror)
			)
		)
		(duplicate_pad_numbers_are_jumpers no)
		(fp_poly
			(pts
				(xy -0.3048 -0.1016) (xy -0.3048 0.9906) (xy 0.3048 0.9906) (xy 0.3048 -0.1016)
			)
			(stroke
				(width 0)
				(type default)
			)
			(fill no)
			(layer "B.CrtYd")
		)
		(fp_line
			(start 0.3048 0.9906)
			(end -0.3048 0.9906)
			(stroke
				(width 0.1)
				(type default)
			)
			(layer "B.Fab")
		)
		(fp_line
			(start 0.3048 -0.1016)
			(end 0.3048 0.9906)
			(stroke
				(width 0.1)
				(type default)
			)
			(layer "B.Fab")
		)
		(fp_line
			(start -0.3048 0.9906)
			(end -0.3048 -0.1016)
			(stroke
				(width 0.1)
				(type default)
			)
			(layer "B.Fab")
		)
		(fp_line
			(start -0.3048 -0.1016)
			(end 0.3048 -0.1016)
			(stroke
				(width 0.1)
				(type default)
			)
			(layer "B.Fab")
		)
		(pad "1" smd rect
			(at 0 0)
			(size 0.508 0.508)
			(layers "B.Cu" "B.Mask" "B.Paste")
			(net "P3V3")
		)
		(pad "2" smd rect
			(at 0 0.889)
			(size 0.508 0.508)
			(layers "B.Cu" "B.Mask" "B.Paste")
			(net "GND")
		)
		(zone
			(layer "B.Cu")
			(hatch none 0.5)
			(connect_pads
				(clearance 0)
			)
			(min_thickness 0.25)
			(keepout
				(tracks not_allowed)
				(vias allowed)
				(pads allowed)
				(copperpour not_allowed)
				(footprints allowed)
			)
			(placement
				(enabled no)
				(sheetname "")
			)
			(fill
				(thermal_gap 0.5)
				(thermal_bridge_width 0.5)
				(island_removal_mode 0)
			)
			(polygon
				(pts
					(xy 363.1946 -63.3349) (xy 363.7026 -63.3349) (xy 363.7026 -62.9539) (xy 363.1946 -62.9539)
				)
			)
		)
		(zone
			(layer "B.Cu")
			(hatch none 0.5)
			(connect_pads
				(clearance 0)
			)
			(min_thickness 0.25)
			(keepout
				(tracks allowed)
				(vias not_allowed)
				(pads allowed)
				(copperpour not_allowed)
				(footprints allowed)
			)
			(placement
				(enabled no)
				(sheetname "")
			)
			(fill
				(thermal_gap 0.5)
				(thermal_bridge_width 0.5)
				(island_removal_mode 0)
			)
			(polygon
				(pts
					(xy 363.1946 -62.9539) (xy 363.7026 -62.9539) (xy 363.7026 -63.3349) (xy 363.1946 -63.3349)
				)
			)
		)
	)
	(footprint ""
		(layer "B.Cu")
		(at 409.1305 -19.812 90)
		(property "Reference" "R1U29"
			(at 0 0 90)
			(layer "B.SilkS")
			(hide yes)
			(effects
				(font
					(size 1.27 1.27)
				)
				(justify mirror)
			)
		)
		(property "Value" ""
			(at 0 0 90)
			(layer "B.Fab")
			(effects
				(font
					(size 1.27 1.27)
				)
				(justify mirror)
			)
		)
		(duplicate_pad_numbers_are_jumpers no)
		(fp_poly
			(pts
				(xy 0.2794 -0.1016) (xy -0.2794 -0.1016) (xy -0.2794 0.9906) (xy 0.2794 0.9906)
			)
			(stroke
				(width 0)
				(type default)
			)
			(fill no)
			(layer "B.CrtYd")
		)
		(fp_line
			(start 0.2794 -0.1016)
			(end 0.2794 0.9906)
			(stroke
				(width 0.1)
				(type default)
			)
			(layer "B.Fab")
		)
		(fp_line
			(start -0.2794 -0.1016)
			(end 0.2794 -0.1016)
			(stroke
				(width 0.1)
				(type default)
			)
			(layer "B.Fab")
		)
		(fp_line
			(start 0.2794 0.9906)
			(end -0.2794 0.9906)
			(stroke
				(width 0.1)
				(type default)
			)
			(layer "B.Fab")
		)
		(fp_line
			(start -0.2794 0.9906)
			(end -0.2794 -0.1016)
			(stroke
				(width 0.1)
				(type default)
			)
			(layer "B.Fab")
		)
		(pad "1" smd rect
			(at 0 0 270)
			(size 0.508 0.508)
			(layers "B.Cu" "B.Mask" "B.Paste")
			(net "P5V")
		)
		(pad "2" smd rect
			(at 0 0.889 270)
			(size 0.508 0.508)
			(layers "B.Cu" "B.Mask" "B.Paste")
			(net "A_P5V_SCALED")
		)
		(zone
			(layer "B.Cu")
			(hatch none 0.5)
			(connect_pads
				(clearance 0)
			)
			(min_thickness 0.25)
			(keepout
				(tracks allowed)
				(vias not_allowed)
				(pads allowed)
				(copperpour not_allowed)
				(footprints allowed)
			)
			(placement
				(enabled no)
				(sheetname "")
			)
			(fill
				(thermal_gap 0.5)
				(thermal_bridge_width 0.5)
				(island_removal_mode 0)
			)
			(polygon
				(pts
					(xy 409.3845 -20.066) (xy 409.3845 -19.558) (xy 409.7655 -19.558) (xy 409.7655 -20.066)
				)
			)
		)
		(zone
			(layer "B.Cu")
			(hatch none 0.5)
			(connect_pads
				(clearance 0)
			)
			(min_thickness 0.25)
			(keepout
				(tracks not_allowed)
				(vias allowed)
				(pads allowed)
				(copperpour not_allowed)
				(footprints allowed)
			)
			(placement
				(enabled no)
				(sheetname "")
			)
			(fill
				(thermal_gap 0.5)
				(thermal_bridge_width 0.5)
				(island_removal_mode 0)
			)
			(polygon
				(pts
					(xy 409.7655 -20.066) (xy 409.7655 -19.558) (xy 409.3845 -19.558) (xy 409.3845 -20.066)
				)
			)
		)
	)
)
